(kicad_pcb
	(version 20260206)
	(generator "pcbnew")
	(generator_version "10.0")
	(general
		(thickness 1.6)
		(legacy_teardrops no)
	)
	(paper "A4")
	(title_block
		(title "netronome-mezz — pcbd0082-001_rev01_jul9_a.brd")
		(comment 1 "Open CloudServer (Microsoft) / footprints 1-6 of 714")
	)
	(layers
		(0 "F.Cu" signal "TOP")
		(4 "In1.Cu" signal "02_GND")
		(6 "In2.Cu" signal "03_SIG")
		(8 "In3.Cu" signal "04_SIG")
		(10 "In4.Cu" signal "05_GND")
		(12 "In5.Cu" signal "06_PWR1")
		(14 "In6.Cu" signal "07_SIG")
		(16 "In7.Cu" signal "08_SIG")
		(18 "In8.Cu" signal "09_GND")
		(2 "B.Cu" signal "BOTTOM")
		(9 "F.Adhes" user "F.Adhesive")
		(11 "B.Adhes" user "B.Adhesive")
		(13 "F.Paste" user "Package Geometry/Pastemask Top")
		(15 "B.Paste" user "Package Geometry/Pastemask Bottom")
		(5 "F.SilkS" user "Ref Des/Silkscreen Top")
		(7 "B.SilkS" user "Ref Des/Silkscreen Bottom")
		(1 "F.Mask" user "Board Geometry/Soldermask Top")
		(3 "B.Mask" user "Board Geometry/Soldermask Bottom")
		(17 "Dwgs.User" user "User.Drawings")
		(19 "Cmts.User" user "User.Comments")
		(21 "Eco1.User" user "User.Eco1")
		(23 "Eco2.User" user "User.Eco2")
		(25 "Edge.Cuts" user "Board Geometry/Outline")
		(27 "Margin" user)
		(31 "F.CrtYd" user "Package Geometry/Place Bound Top")
		(29 "B.CrtYd" user "Package Geometry/Place Bound Bottom")
		(35 "F.Fab" user "Ref Des/Assembly Top")
		(33 "B.Fab" user "Ref Des/Assembly Bottom")
		(45 "User.4" user "COMPVAL_TYPE_BOTTOM")
	)
	(footprint ""
		(layer "F.Cu")
		(at 22.1488 22.479 90)
		(property "Reference" "U15"
			(at 3.65633 -5.0038 0)
			(unlocked yes)
			(layer "F.SilkS")
			(effects
				(font
					(size 0.7874 0.5842)
					(thickness 0.127)
				)
				(justify left)
			)
		)
		(property "Value" "*"
			(at -0.4826 1.375842 90)
			(unlocked yes)
			(layer "F.Fab")
			(hide yes)
			(effects
				(font
					(size 1.27 0.9652)
					(thickness 0.000001)
				)
				(justify left)
			)
		)
		(property "Device Type" "PROG0055"
			(at -0.4826 1.375842 90)
			(unlocked yes)
			(layer "F.Fab")
			(hide yes)
			(effects
				(font
					(size 1.27 0.9652)
					(thickness 0.000001)
				)
				(justify left)
			)
		)
		(duplicate_pad_numbers_are_jumpers no)
		(fp_line
			(start 3.048 -3.048)
			(end 3.048 -2.54)
			(stroke
				(width 0.2032)
				(type default)
			)
			(layer "F.SilkS")
		)
		(fp_line
			(start -0.587858 -3.048)
			(end 3.048 -3.048)
			(stroke
				(width 0.2032)
				(type default)
			)
			(layer "F.SilkS")
		)
		(fp_line
			(start -0.762 -3.048)
			(end -0.762 -2.286)
			(stroke
				(width 0.2032)
				(type default)
			)
			(layer "F.SilkS")
		)
		(fp_line
			(start -1.755775 -3.048)
			(end -0.936142 -3.048)
			(stroke
				(width 0.2032)
				(type default)
			)
			(layer "F.SilkS")
		)
		(fp_line
			(start -3.048 -3.048)
			(end 3.048 -3.048)
			(stroke
				(width 0.2032)
				(type default)
			)
			(layer "F.SilkS")
		)
		(fp_line
			(start -3.048 -2.54)
			(end -3.048 -3.048)
			(stroke
				(width 0.2032)
				(type default)
			)
			(layer "F.SilkS")
		)
		(fp_line
			(start 0.762 -2.286)
			(end 0.762 -3.048)
			(stroke
				(width 0.2032)
				(type default)
			)
			(layer "F.SilkS")
		)
		(fp_line
			(start 0.762 -2.286)
			(end 0.762 -3.048)
			(stroke
				(width 0.2032)
				(type default)
			)
			(layer "F.SilkS")
		)
		(fp_line
			(start -0.178918 -2.286)
			(end 0.762 -2.286)
			(stroke
				(width 0.2032)
				(type default)
			)
			(layer "F.SilkS")
		)
		(fp_line
			(start -0.762 -2.286)
			(end 0.762 -2.286)
			(stroke
				(width 0.2032)
				(type default)
			)
			(layer "F.SilkS")
		)
		(fp_line
			(start 3.048 2.54)
			(end 3.048 3.048)
			(stroke
				(width 0.2032)
				(type default)
			)
			(layer "F.SilkS")
		)
		(fp_line
			(start 3.048 3.048)
			(end -3.048 3.048)
			(stroke
				(width 0.2032)
				(type default)
			)
			(layer "F.SilkS")
		)
		(fp_line
			(start 3.048 3.048)
			(end -3.048 3.048)
			(stroke
				(width 0.2032)
				(type default)
			)
			(layer "F.SilkS")
		)
		(fp_line
			(start -3.048 3.048)
			(end -3.048 2.54)
			(stroke
				(width 0.2032)
				(type default)
			)
			(layer "F.SilkS")
		)
		(fp_circle
			(center -4.064 -2.667)
			(end -4.064 -2.413)
			(stroke
				(width 0.2032)
				(type default)
			)
			(fill no)
			(layer "F.SilkS")
		)
		(fp_poly
			(pts
				(xy -3.302 3.302) (xy 3.302 3.302) (xy 3.302 2.794) (xy 5.08 2.794) (xy 5.08 -2.794) (xy 3.302 -2.794)
				(xy 3.302 -3.302) (xy -3.302 -3.302) (xy -3.302 -2.794) (xy -5.08 -2.794) (xy -5.08 2.794) (xy -3.302 2.794)
			)
			(stroke
				(width 0)
				(type default)
			)
			(fill no)
			(layer "F.CrtYd")
		)
		(fp_line
			(start 2.7432 -2.7432)
			(end -2.7432 -2.7432)
			(stroke
				(width 0.2032)
				(type default)
			)
			(layer "F.Fab")
		)
		(fp_line
			(start -2.7432 -2.7432)
			(end -2.7432 2.7432)
			(stroke
				(width 0.2032)
				(type default)
			)
			(layer "F.Fab")
		)
		(fp_line
			(start -0.762 -2.667)
			(end -0.762 -1.905)
			(stroke
				(width 0.2032)
				(type default)
			)
			(layer "F.Fab")
		)
		(fp_line
			(start 0.762 -1.905)
			(end 0.762 -2.667)
			(stroke
				(width 0.2032)
				(type default)
			)
			(layer "F.Fab")
		)
		(fp_line
			(start -0.762 -1.905)
			(end 0.762 -1.905)
			(stroke
				(width 0.2032)
				(type default)
			)
			(layer "F.Fab")
		)
		(fp_line
			(start 2.7432 2.7432)
			(end 2.7432 -2.7432)
			(stroke
				(width 0.2032)
				(type default)
			)
			(layer "F.Fab")
		)
		(fp_line
			(start -2.7432 2.7432)
			(end 2.7432 2.7432)
			(stroke
				(width 0.2032)
				(type default)
			)
			(layer "F.Fab")
		)
		(fp_circle
			(center -1.905 -1.905)
			(end -1.905 -1.524)
			(stroke
				(width 0.2032)
				(type default)
			)
			(fill no)
			(layer "F.Fab")
		)
		(pad "1" smd rect
			(at -3.6449 -1.905 90)
			(size 1.8288 0.635)
			(layers "F.Cu" "F.Mask" "F.Paste")
			(net "NFP_ARM_SPI_FLASH_SEL")
		)
		(pad "2" smd rect
			(at -3.6449 -0.635 90)
			(size 1.8288 0.635)
			(layers "F.Cu" "F.Mask" "F.Paste")
			(net "NFP_ARM_SPI_FLASH_MISO")
		)
		(pad "3" smd rect
			(at -3.6449 0.635 90)
			(size 1.8288 0.635)
			(layers "F.Cu" "F.Mask" "F.Paste")
			(net "NFP_ARM_SPI_FLASH_WP_L")
		)
		(pad "4" smd rect
			(at -3.6449 1.905 90)
			(size 1.8288 0.635)
			(layers "F.Cu" "F.Mask" "F.Paste")
			(net "GND")
		)
		(pad "5" smd rect
			(at 3.6449 1.905 90)
			(size 1.8288 0.635)
			(layers "F.Cu" "F.Mask" "F.Paste")
			(net "NFP_ARM_SPI_FLASH_MOSI")
		)
		(pad "6" smd rect
			(at 3.6449 0.635 90)
			(size 1.8288 0.635)
			(layers "F.Cu" "F.Mask" "F.Paste")
			(net "NFP_ARM_SPI_FLASH_SCK")
		)
		(pad "7" smd rect
			(at 3.6449 -0.635 90)
			(size 1.8288 0.635)
			(layers "F.Cu" "F.Mask" "F.Paste")
			(net "3N2521")
		)
		(pad "8" smd rect
			(at 3.6449 -1.905 90)
			(size 1.8288 0.635)
			(layers "F.Cu" "F.Mask" "F.Paste")
			(net "VDD_3.3V")
		)
	)
	(footprint ""
		(layer "F.Cu")
		(at 78.3082 49.53 90)
		(property "Reference" "C66"
			(at -1.67767 -0.3302 0)
			(unlocked yes)
			(layer "F.SilkS")
			(effects
				(font
					(size 0.7874 0.5842)
					(thickness 0.127)
				)
				(justify left)
			)
		)
		(property "Value" "100UF"
			(at -0.78232 0.4826 180)
			(unlocked yes)
			(layer "F.Fab")
			(hide yes)
			(effects
				(font
					(size 1.27 0.9652)
					(thickness 0.000001)
				)
				(justify left)
			)
		)
		(property "Device Type" "CAPC0087"
			(at -0.78232 0.4826 180)
			(unlocked yes)
			(layer "F.Fab")
			(hide yes)
			(effects
				(font
					(size 1.27 0.9652)
					(thickness 0.000001)
				)
				(justify left)
			)
		)
		(duplicate_pad_numbers_are_jumpers no)
		(fp_circle
			(center 0 0)
			(end 0 0.508)
			(stroke
				(width 0.2032)
				(type default)
			)
			(fill no)
			(layer "F.SilkS")
		)
		(fp_circle
			(center 0 0)
			(end 0 0.508)
			(stroke
				(width 0.2032)
				(type default)
			)
			(fill no)
			(layer "F.SilkS")
		)
		(fp_poly
			(pts
				(xy -1.27 2.9464) (xy 1.27 2.9464) (xy 1.27 -2.795295) (xy -1.27 -2.795295)
			)
			(stroke
				(width 0)
				(type default)
			)
			(fill no)
			(layer "F.CrtYd")
		)
		(fp_line
			(start 1.016 -2.794)
			(end 1.016 2.794)
			(stroke
				(width 0.0254)
				(type default)
			)
			(layer "F.Fab")
		)
		(fp_line
			(start -1.016 -2.794)
			(end 1.016 -2.794)
			(stroke
				(width 0.0254)
				(type default)
			)
			(layer "F.Fab")
		)
		(fp_line
			(start 1.016 2.794)
			(end -1.016 2.794)
			(stroke
				(width 0.0254)
				(type default)
			)
			(layer "F.Fab")
		)
		(fp_line
			(start -1.016 2.794)
			(end -1.016 -2.794)
			(stroke
				(width 0.0254)
				(type default)
			)
			(layer "F.Fab")
		)
		(pad "1" smd rect
			(at 0 -1.6764 90)
			(size 1.524 1.524)
			(layers "F.Cu" "F.Mask" "F.Paste")
			(net "DDR_VDDQ")
		)
		(pad "2" smd rect
			(at 0 1.6764 90)
			(size 1.524 1.524)
			(layers "F.Cu" "F.Mask" "F.Paste")
			(net "GND")
		)
		(zone
			(layer "F.Cu")
			(hatch none 0.5)
			(connect_pads
				(clearance 0)
			)
			(min_thickness 0.25)
			(keepout
				(tracks not_allowed)
				(vias allowed)
				(pads allowed)
				(copperpour not_allowed)
				(footprints allowed)
			)
			(placement
				(enabled no)
				(sheetname "")
			)
			(fill
				(thermal_gap 0.5)
				(thermal_bridge_width 0.5)
				(island_removal_mode 0)
			)
			(polygon
				(pts
					(xy 77.4192 50.3174) (xy 77.4192 48.7426) (xy 77.5716 48.7426) (xy 77.5716 50.3174)
				)
			)
		)
		(zone
			(layer "F.Cu")
			(hatch none 0.5)
			(connect_pads
				(clearance 0)
			)
			(min_thickness 0.25)
			(keepout
				(tracks not_allowed)
				(vias allowed)
				(pads allowed)
				(copperpour not_allowed)
				(footprints allowed)
			)
			(placement
				(enabled no)
				(sheetname "")
			)
			(fill
				(thermal_gap 0.5)
				(thermal_bridge_width 0.5)
				(island_removal_mode 0)
			)
			(polygon
				(pts
					(xy 79.0448 50.3174) (xy 79.0448 48.7426) (xy 79.1972 48.7426) (xy 79.1972 50.3174)
				)
			)
		)
		(zone
			(layer "F.Cu")
			(hatch none 0.5)
			(connect_pads
				(clearance 0)
			)
			(min_thickness 0.25)
			(keepout
				(tracks allowed)
				(vias not_allowed)
				(pads allowed)
				(copperpour not_allowed)
				(footprints allowed)
			)
			(placement
				(enabled no)
				(sheetname "")
			)
			(fill
				(thermal_gap 0.5)
				(thermal_bridge_width 0.5)
				(island_removal_mode 0)
			)
			(polygon
				(pts
					(xy 79.9084 50.3174) (xy 79.9084 48.7426) (xy 76.708 48.7426) (xy 76.708 50.3174)
				)
			)
		)
	)
	(footprint ""
		(layer "F.Cu")
		(at 17.78 24.384 180)
		(property "Reference" "R395"
			(at 0.48133 1.27 90)
			(unlocked yes)
			(layer "F.SilkS")
			(effects
				(font
					(size 0.7874 0.5842)
					(thickness 0.127)
				)
				(justify left)
			)
		)
		(property "Value" "4.75K"
			(at -0.148158 1.3462 270)
			(unlocked yes)
			(layer "F.Fab")
			(hide yes)
			(effects
				(font
					(size 1.27 0.9652)
					(thickness 0.000001)
				)
				(justify left)
			)
		)
		(property "Device Type" "REST4024"
			(at -0.148158 1.3462 270)
			(unlocked yes)
			(layer "F.Fab")
			(hide yes)
			(effects
				(font
					(size 1.27 0.9652)
					(thickness 0.000001)
				)
				(justify left)
			)
		)
		(duplicate_pad_numbers_are_jumpers no)
		(fp_poly
			(pts
				(xy 0.635 1.0668) (xy 0.635 -1.0668) (xy -0.635 -1.0668) (xy -0.635 1.0668)
			)
			(stroke
				(width 0)
				(type default)
			)
			(fill no)
			(layer "F.CrtYd")
		)
		(fp_line
			(start 0.254 0.508)
			(end -0.254 0.508)
			(stroke
				(width 0.0254)
				(type default)
			)
			(layer "F.Fab")
		)
		(fp_line
			(start 0.254 -0.508)
			(end 0.254 0.508)
			(stroke
				(width 0.0254)
				(type default)
			)
			(layer "F.Fab")
		)
		(fp_line
			(start -0.254 0.508)
			(end -0.254 -0.508)
			(stroke
				(width 0.0254)
				(type default)
			)
			(layer "F.Fab")
		)
		(fp_line
			(start -0.254 -0.508)
			(end 0.254 -0.508)
			(stroke
				(width 0.0254)
				(type default)
			)
			(layer "F.Fab")
		)
		(pad "1" smd rect
			(at 0 -0.4191 180)
			(size 0.508 0.5334)
			(layers "F.Cu" "F.Mask" "F.Paste")
			(net "EXT_3.3V")
		)
		(pad "2" smd rect
			(at 0 0.4191 180)
			(size 0.508 0.5334)
			(layers "F.Cu" "F.Mask" "F.Paste")
			(net "CPLD_NIC_MEZZ_ID1")
		)
		(zone
			(layer "F.Cu")
			(hatch none 0.5)
			(connect_pads
				(clearance 0)
			)
			(min_thickness 0.25)
			(keepout
				(tracks not_allowed)
				(vias allowed)
				(pads allowed)
				(copperpour not_allowed)
				(footprints allowed)
			)
			(placement
				(enabled no)
				(sheetname "")
			)
			(fill
				(thermal_gap 0.5)
				(thermal_bridge_width 0.5)
				(island_removal_mode 0)
			)
			(polygon
				(pts
					(xy 17.7546 24.4094) (xy 17.7546 24.3586) (xy 17.8054 24.3586) (xy 17.8054 24.4094)
				)
			)
		)
	)
	(footprint ""
		(layer "F.Cu")
		(at 11.811 33.528 -90)
		(property "Reference" "C134"
			(at -0.98933 1.524 0)
			(unlocked yes)
			(layer "F.SilkS")
			(effects
				(font
					(size 0.7874 0.5842)
					(thickness 0.127)
				)
				(justify left)
			)
		)
		(property "Value" "10UF"
			(at -0.148158 1.7526 0)
			(unlocked yes)
			(layer "F.Fab")
			(hide yes)
			(effects
				(font
					(size 1.27 0.9652)
					(thickness 0.000001)
				)
				(justify left)
			)
		)
		(property "Device Type" "CAPC0058"
			(at -0.148158 1.7526 0)
			(unlocked yes)
			(layer "F.Fab")
			(hide yes)
			(effects
				(font
					(size 1.27 0.9652)
					(thickness 0.000001)
				)
				(justify left)
			)
		)
		(duplicate_pad_numbers_are_jumpers no)
		(fp_circle
			(center 0 0)
			(end 0 -0.127)
			(stroke
				(width 0.2032)
				(type default)
			)
			(fill no)
			(layer "F.SilkS")
		)
		(fp_poly
			(pts
				(xy 0.7874 -1.6637) (xy -0.7874 -1.6637) (xy -0.7874 1.6637) (xy 0.7874 1.6637)
			)
			(stroke
				(width 0)
				(type default)
			)
			(fill no)
			(layer "F.CrtYd")
		)
		(fp_line
			(start -0.4064 0.8128)
			(end -0.4064 -0.7874)
			(stroke
				(width 0.0254)
				(type default)
			)
			(layer "F.Fab")
		)
		(fp_line
			(start 0.4064 0.8128)
			(end -0.4064 0.8128)
			(stroke
				(width 0.0254)
				(type default)
			)
			(layer "F.Fab")
		)
		(fp_line
			(start -0.4064 -0.7874)
			(end 0.4064 -0.7874)
			(stroke
				(width 0.0254)
				(type default)
			)
			(layer "F.Fab")
		)
		(fp_line
			(start 0.4064 -0.7874)
			(end 0.4064 0.8128)
			(stroke
				(width 0.0254)
				(type default)
			)
			(layer "F.Fab")
		)
		(pad "1" smd rect
			(at 0 -0.8001 270)
			(size 0.8636 0.9652)
			(layers "F.Cu" "F.Mask" "F.Paste")
			(net "VDD_5.0V")
		)
		(pad "2" smd rect
			(at 0 0.8001 270)
			(size 0.8636 0.9652)
			(layers "F.Cu" "F.Mask" "F.Paste")
			(net "GND")
		)
	)
	(footprint ""
		(layer "F.Cu")
		(at 30.099 32.639)
		(property "Reference" "R96"
			(at 0 0 0)
			(layer "F.SilkS")
			(hide yes)
			(effects
				(font
					(size 1.27 1.27)
				)
			)
		)
		(property "Value" "4.75K"
			(at -0.148158 1.3462 90)
			(unlocked yes)
			(layer "F.Fab")
			(hide yes)
			(effects
				(font
					(size 1.27 0.9652)
					(thickness 0.000001)
				)
				(justify left)
			)
		)
		(property "Device Type" "REST4024"
			(at -0.148158 1.3462 90)
			(unlocked yes)
			(layer "F.Fab")
			(hide yes)
			(effects
				(font
					(size 1.27 0.9652)
					(thickness 0.000001)
				)
				(justify left)
			)
		)
		(duplicate_pad_numbers_are_jumpers no)
		(fp_poly
			(pts
				(xy 0.635 1.0668) (xy 0.635 -1.0668) (xy -0.635 -1.0668) (xy -0.635 1.0668)
			)
			(stroke
				(width 0)
				(type default)
			)
			(fill no)
			(layer "F.CrtYd")
		)
		(fp_line
			(start -0.254 -0.508)
			(end 0.254 -0.508)
			(stroke
				(width 0.0254)
				(type default)
			)
			(layer "F.Fab")
		)
		(fp_line
			(start -0.254 0.508)
			(end -0.254 -0.508)
			(stroke
				(width 0.0254)
				(type default)
			)
			(layer "F.Fab")
		)
		(fp_line
			(start 0.254 -0.508)
			(end 0.254 0.508)
			(stroke
				(width 0.0254)
				(type default)
			)
			(layer "F.Fab")
		)
		(fp_line
			(start 0.254 0.508)
			(end -0.254 0.508)
			(stroke
				(width 0.0254)
				(type default)
			)
			(layer "F.Fab")
		)
		(pad "1" smd rect
			(at 0 -0.4191)
			(size 0.508 0.5334)
			(layers "F.Cu" "F.Mask" "F.Paste")
			(net "GND")
		)
		(pad "2" smd rect
			(at 0 0.4191)
			(size 0.508 0.5334)
			(layers "F.Cu" "F.Mask" "F.Paste")
			(net "_NFP_CORE_VID2")
		)
		(zone
			(layer "F.Cu")
			(hatch none 0.5)
			(connect_pads
				(clearance 0)
			)
			(min_thickness 0.25)
			(keepout
				(tracks not_allowed)
				(vias allowed)
				(pads allowed)
				(copperpour not_allowed)
				(footprints allowed)
			)
			(placement
				(enabled no)
				(sheetname "")
			)
			(fill
				(thermal_gap 0.5)
				(thermal_bridge_width 0.5)
				(island_removal_mode 0)
			)
			(polygon
				(pts
					(xy 30.1244 32.6136) (xy 30.1244 32.6644) (xy 30.0736 32.6644) (xy 30.0736 32.6136)
				)
			)
		)
	)
	(footprint ""
		(layer "F.Cu")
		(at 76.708 29.083 -90)
		(property "Reference" "R7"
			(at 0.91567 -0.508 0)
			(unlocked yes)
			(layer "F.SilkS")
			(effects
				(font
					(size 0.7874 0.5842)
					(thickness 0.127)
				)
				(justify left)
			)
		)
		(property "Value" "36.0"
			(at -0.148158 1.3462 0)
			(unlocked yes)
			(layer "F.Fab")
			(hide yes)
			(effects
				(font
					(size 1.27 0.9652)
					(thickness 0.000001)
				)
				(justify left)
			)
		)
		(property "Device Type" "REST0125"
			(at -0.148158 1.3462 0)
			(unlocked yes)
			(layer "F.Fab")
			(hide yes)
			(effects
				(font
					(size 1.27 0.9652)
					(thickness 0.000001)
				)
				(justify left)
			)
		)
		(duplicate_pad_numbers_are_jumpers no)
		(fp_poly
			(pts
				(xy 0.635 1.0668) (xy 0.635 -1.0668) (xy -0.635 -1.0668) (xy -0.635 1.0668)
			)
			(stroke
				(width 0)
				(type default)
			)
			(fill no)
			(layer "F.CrtYd")
		)
		(fp_line
			(start -0.254 0.508)
			(end -0.254 -0.508)
			(stroke
				(width 0.0254)
				(type default)
			)
			(layer "F.Fab")
		)
		(fp_line
			(start 0.254 0.508)
			(end -0.254 0.508)
			(stroke
				(width 0.0254)
				(type default)
			)
			(layer "F.Fab")
		)
		(fp_line
			(start -0.254 -0.508)
			(end 0.254 -0.508)
			(stroke
				(width 0.0254)
				(type default)
			)
			(layer "F.Fab")
		)
		(fp_line
			(start 0.254 -0.508)
			(end 0.254 0.508)
			(stroke
				(width 0.0254)
				(type default)
			)
			(layer "F.Fab")
		)
		(pad "1" smd rect
			(at 0 -0.4191 270)
			(size 0.508 0.5334)
			(layers "F.Cu" "F.Mask" "F.Paste")
			(net "DDR0_32A_CK0_P")
		)
		(pad "2" smd rect
			(at 0 0.4191 270)
			(size 0.508 0.5334)
			(layers "F.Cu" "F.Mask" "F.Paste")
			(net "6N4748")
		)
		(zone
			(layer "F.Cu")
			(hatch none 0.5)
			(connect_pads
				(clearance 0)
			)
			(min_thickness 0.25)
			(keepout
				(tracks not_allowed)
				(vias allowed)
				(pads allowed)
				(copperpour not_allowed)
				(footprints allowed)
			)
			(placement
				(enabled no)
				(sheetname "")
			)
			(fill
				(thermal_gap 0.5)
				(thermal_bridge_width 0.5)
				(island_removal_mode 0)
			)
			(polygon
				(pts
					(xy 76.7334 29.1084) (xy 76.6826 29.1084) (xy 76.6826 29.0576) (xy 76.7334 29.0576)
				)
			)
		)
	)
)
